FILE_TYPE = CONNECTIVITY;
{Allegro Design Entry HDL 17.2-2016 S081 (4005846) 1/11/2022}
"PAGE_NUMBER" = 271;
0"NC";
1"PVCCIN_CPU1_PVCC\g";
2"P5V\g";
3"P3V3\g";
4"SW_P12V_PVCCIN_CPU1_FLT\g";
5"PVCCIN_CPU1\g";
6"PVCCIN_CPU1\g";
7"SW_P12V_PVCCIN_CPU1_FLT\g";
8"P12V_AUX\g";
9"PVCCIN_CPU1\g";
10"PVCCIN_CPU1\g";
11"SW_P12V_PVCCIN_CPU1_FLT\g";
12"GND\g";
13"GND\g";
14"GND\g";
15"GND\g";
16"GND\g";
17"GND\g";
18"GND\g";
19"GND\g";
20"GND\g";
21"GND\g";
22"GND\g";
23"GND\g";
24"GND\g";
25"GND\g";
26"GND\g";
27"GND\g";
28"GND\g";
29"GND\g";
30"IND_P1_CPL6";
31"IND_P1_CPL1";
32"IND_P1_CPL1";
33"SW_PVCCIN_CPU1_BOOT1_R";
34"PVCCIN_CPU1_VOS1";
35"SW_PVCCIN_CPU1_BOOTR1";
36"SW_PVCCIN_CPU1_BOOT1";
37"SW_PVCCIN_CPU1_SW1";
38"PVCCIN_CPU1_PVCC";
39"PVCCIN_CPU1_VDD1";
40"PVCCIN_CPU1_PWM1";
41"PVCCIN_CPU1_ATSEN";
42"PVCCIN_CPU1_IMON1";
43"PVCCIN_CPU1_VREF"CDS_PHYS_NET_NAME"PVCCIN_CPU1_VREF";
44"PVCCIN_CPU1_LSET1";
45"SW_PVCCIN_CPU1_BOOT2_R";
46"SW_PVCCIN_CPU1_SW2";
47"SW_PVCCIN_CPU1_BOOTR2"CDS_PHYS_NET_NAME"SW_PVCCIN_CPU1_BOOTR2";
48"SW_PVCCIN_CPU1_BOOT2"CDS_PHYS_NET_NAME"SW_PVCCIN_CPU1_BOOT2";
49"IND_P1_CPL2";
50"PVCCIN_CPU1_VOS2";
51"PVCCIN_CPU1_VDD2";
52"PVCCIN_CPU1_IMON2";
53"PVCCIN_CPU1_VREF"CDS_PHYS_NET_NAME"PVCCIN_CPU1_VREF";
54"PVCCIN_CPU1_PWM2";
55"PVCCIN_CPU1_ATSEN";
56"PVCCIN_CPU1_LSET2";
%"UNIVERSAL_GND"
"1","(-4150,-1975)","0","logical_power","I1";
;
HDL_POWER"GND"
CDS_LIB"logical_power";
"A"12;
%"UNIVERSAL_GND"
"1","(-3650,-1450)","0","logical_power","I10";
;
HDL_POWER"GND"
CDS_LIB"logical_power";
"A"14;
%"Q_CAP"
"1","(-3650,-1200)","0","pure_quanta","I11";
;
PART_NUMBER"CH5222KEB01"
PACK_TYPE"C0402"
VOLTAGE"10V"
VALUE"2.2UF"
TOLERANCE"10%"
MATERIAL"X6S"
LOCATION"PC556"
CDS_LIB"pure_quanta"
LOCATION"PC556"
$SEC"1"
CDS_SEC"1";
"B"
$PN"2"14;
"A"
$PN"1"51;
%"UNIVERSAL_GND"
"1","(-3225,-925)","0","logical_power","I12";
;
HDL_POWER"GND"
CDS_LIB"logical_power";
"A"15;
%"Q_RES"
"2","(-3650,-700)","0","pure_quanta","I13";
;
PART_NUMBER"CS-2202FB01"
PACK_TYPE"0402LF"
TOLERANCE"1%"
MATERIAL"CHIP"
WATTAGE"1/16W"
VALUE"2.2"
LOCATION"PR327"
CDS_LIB"pure_quanta"
LOCATION"PR327"
$SEC"1"
CDS_SEC"1";
"A"
$PN"1"1;
"B"
$PN"2"51;
%"VCC15"
"1","(-3650,-375)","0","logical_power","I14";
;
HDL_POWER"PVCCIN_CPU1_PVCC"
CDS_LIB"logical_power";
"A"1;
%"Q_CAP"
"1","(-3225,-700)","0","pure_quanta","I15";
;
PART_NUMBER"CH5222KEB01"
PACK_TYPE"C0402"
VALUE"2.2UF"
TOLERANCE"10%"
MATERIAL"X6S"
VOLTAGE"10V"
LOCATION"PC558_P1_2"
CDS_LIB"pure_quanta"
LOCATION"PC558_P1_2"
$SEC"1"
CDS_SEC"1";
"B"
$PN"2"15;
"A"
$PN"1"1;
%"UNIVERSAL_GND"
"1","(-1475,-2425)","0","logical_power","I16";
;
HDL_POWER"GND"
CDS_LIB"logical_power";
"A"16;
%"Q_INDUCTOR4P_14"
"1","(300,-1825)","0","pure_quanta","I18";
;
PART_NUMBER"CV+15^0TZ04"
MATERIAL"IND"
PART_TYPE"SMLF"
VALUE"150NH"
LOCATION"PL30"
SEC_TYPE""
CDS_LIB"pure_quanta"
NEEDS_NO_SIZE"TRUE"
SEC"1";
"1"
$PN"1"46;
"4"
$PN"4"5;
"3"
$PN"3"31;
"2"
$PN"2"49;
%"Q_CAP"
"1","(-1325,-800)","0","pure_quanta","I19";
;
PART_NUMBER"TMP_QCH2336K1B12"
PACK_TYPE"0402"
VOLTAGE"50V"
VALUE"3300PF"
TOLERANCE"10%"
MATERIAL"X7R"
LOCATION"PC560_P1_2"
CDS_LIB"pure_quanta"
LOCATION"PC560_P1_2"
$SEC"1"
CDS_SEC"1";
"B"
$PN"2"22;
"A"
$PN"1"4;
%"UNIVERSAL_GND"
"1","(-4050,-2425)","0","logical_power","I2";
;
HDL_POWER"GND"
CDS_LIB"logical_power";
"A"13;
%"Q_RES"
"1","(-875,-1250)","0","pure_quanta","I20";
;
PART_NUMBER"CS-3302FB01"
MATERIAL"CHIP"
PACK_TYPE"0402LF"
VALUE"3.3"
WATTAGE"1/16W"
TOLERANCE"1%"
LOCATION"PR1766"
CDS_LIB"pure_quanta"
$SEC"1"
CDS_SEC"1";
"B"
$PN"2"45;
"A"
$PN"1"48;
%"Q_CAP"
"1","(-925,-800)","0","pure_quanta","I21";
;
PART_NUMBER"CH5103KEB01"
VOLTAGE"16V"
VALUE"1UF"
TOLERANCE"10%"
MATERIAL"X6S"
PACK_TYPE"C0402"
LOCATION"PC562_P1_2"
CDS_LIB"pure_quanta"
LOCATION"PC562_P1_2"
$SEC"1"
CDS_SEC"1";
"B"
$PN"2"22;
"A"
$PN"1"4;
%"Q_CAP"
"1","(-525,-800)","0","pure_quanta","I22";
;
PART_NUMBER"CH6223MEA01"
TOLERANCE"20%"
PACK_TYPE"C0805"
VOLTAGE"16V"
VALUE"22UF"
MATERIAL"X6S"
LOCATION"PC566_P1_2"
CDS_LIB"pure_quanta"
LOCATION"PC566_P1_2"
$SEC"1"
CDS_SEC"1";
"B"
$PN"2"22;
"A"
$PN"1"4;
%"Q_CAP"
"1","(-150,-1425)","2","pure_quanta","I23";
;
PART_NUMBER"CH4106K1B01"
PACK_TYPE"C0402"
MATERIAL"X7R"
VOLTAGE"50V"
TOLERANCE"10%"
VALUE"100NF"
LOCATION"PC564"
CDS_LIB"pure_quanta"
LOCATION"PC564"
$SEC"1"
CDS_SEC"1";
"B"
$PN"2"47;
"A"
$PN"1"45;
%"Q_CAP"
"1","(-125,-800)","0","pure_quanta","I24";
;
PART_NUMBER"CH6223MEA01"
TOLERANCE"20%"
MATERIAL"X6S"
PACK_TYPE"C0805"
VOLTAGE"16V"
VALUE"22UF"
LOCATION"PC568_P1_2"
CDS_LIB"pure_quanta"
LOCATION"PC568_P1_2"
$SEC"1"
CDS_SEC"1";
"B"
$PN"2"22;
"A"
$PN"1"4;
%"UNIVERSAL_GND"
"1","(-4125,850)","0","logical_power","I25";
;
HDL_POWER"GND"
CDS_LIB"logical_power";
"A"17;
%"Q_RES"
"2","(-4125,2800)","0","pure_quanta","I26";
;
PART_NUMBER"CS00002JB13"
PACK_TYPE"0402LF"
VALUE"0"
TOLERANCE"5%"
MATERIAL"CHIP"
WATTAGE"1/16W"
LOCATION"PR639"
CDS_LIB"pure_quanta"
$SEC"1"
CDS_SEC"1";
"A"
$PN"1"2;
"B"
$PN"2"38;
%"VCC15"
"1","(-4125,3025)","0","logical_power","I27";
;
HDL_POWER"P5V"
CDS_LIB"logical_power";
"A"2;
%"UNIVERSAL_GND"
"1","(-4025,400)","0","logical_power","I28";
;
HDL_POWER"GND"
CDS_LIB"logical_power";
"A"18;
%"Q_RES"
"2","(-4025,625)","2","pure_quanta","I29";
;
PART_NUMBER"CS28872FB01"
PACK_TYPE"0402LF"
VALUE"8.87K"
TOLERANCE"1%"
MATERIAL"EMPTY"
WATTAGE"1/16W"
LOCATION"PR326"
CDS_LIB"pure_quanta"
LOCATION"PR326"
$SEC"1"
CDS_SEC"1";
"A"
$PN"1"44;
"B"
$PN"2"18;
%"Q_RES"
"2","(-4050,-2200)","2","pure_quanta","I3";
;
PART_NUMBER"CS28872FB01"
PACK_TYPE"0402LF"
VALUE"8.87K"
TOLERANCE"1%"
MATERIAL"EMPTY"
WATTAGE"1/16W"
LOCATION"PR325"
CDS_LIB"pure_quanta"
LOCATION"PR325"
$SEC"1"
CDS_SEC"1";
"A"
$PN"1"56;
"B"
$PN"2"13;
%"Q_CAP"
"2","(-3300,925)","0","pure_quanta","I34";
;
PART_NUMBER"CH4104K1B00"
TOLERANCE"10%"
MATERIAL"X7R"
VALUE"0.1UF"
VOLTAGE"25V"
PACK_TYPE"0402"
LOCATION"PC1339"
CDS_LIB"pure_quanta"
$SEC"1"
CDS_SEC"1";
"A"
$PN"1"17;
"B"
$PN"2"43;
%"UNIVERSAL_GND"
"1","(-3625,1375)","0","logical_power","I35";
;
HDL_POWER"GND"
CDS_LIB"logical_power";
"A"19;
%"Q_CAP"
"1","(-3625,1625)","0","pure_quanta","I36";
;
PART_NUMBER"CH5222KEB01"
PACK_TYPE"C0402"
VOLTAGE"10V"
VALUE"2.2UF"
MATERIAL"X6S"
TOLERANCE"10%"
LOCATION"PC557"
CDS_LIB"pure_quanta"
LOCATION"PC557"
$SEC"1"
CDS_SEC"1";
"B"
$PN"2"19;
"A"
$PN"1"39;
%"Q_RES"
"2","(-3625,2125)","0","pure_quanta","I37";
;
PART_NUMBER"CS-2202FB01"
PACK_TYPE"0402LF"
VALUE"2.2"
TOLERANCE"1%"
MATERIAL"CHIP"
WATTAGE"1/16W"
LOCATION"PR328"
CDS_LIB"pure_quanta"
LOCATION"PR328"
$SEC"1"
CDS_SEC"1";
"A"
$PN"1"38;
"B"
$PN"2"39;
%"UNIVERSAL_GND"
"1","(-3200,1900)","0","logical_power","I38";
;
HDL_POWER"GND"
CDS_LIB"logical_power";
"A"20;
%"Q_CAP"
"1","(-3200,2125)","0","pure_quanta","I39";
;
PART_NUMBER"CH5222KEB01"
PACK_TYPE"C0402"
VOLTAGE"10V"
VALUE"2.2UF"
TOLERANCE"10%"
MATERIAL"X6S"
LOCATION"PC559_P1_1"
CDS_LIB"pure_quanta"
LOCATION"PC559_P1_1"
$SEC"1"
CDS_SEC"1";
"B"
$PN"2"20;
"A"
$PN"1"38;
%"ISL99390FRZTR5935"
"1","(-2100,1125)","0","pure_quanta","I40";
;
PART_NUMBER"AL099390004"
VALUE"ISL99390FRZ-TR5935"
MATERIAL"IC"
PART_TYPE"SMLF"
LOCATION"PU31_P1_1"
CDS_LIB"pure_quanta"
CDS_LMAN_SYM_OUTLINE"-300,700,250,-650"
NEEDS_NO_SIZE"TRUE"
$SEC"1"
CDS_SEC"1";
"PGND2"
$PN"7_9-20_24"21;
"GL2"
$PN"41"0;
"GL1"
$PN"6"0;
"DNC"
$PN"31"0;
"EN"
$PN"35"39;
"PGND3"
$PN"40"21;
"VOS"
$PN"1"34;
"VIN2"
$PN"30"7;
"PGND1"
$PN"5"21;
"SW"
$PN"10_19"37;
"LSET"
$PN"37"44;
"IOUT"
$PN"38"42;
"TOUT_FLT"
$PN"36"41;
"PVCC"
$PN"4"38;
"PHASE"
$PN"32"35;
"VIN1"
$PN"25_29"7;
"BOOT"
$PN"33"36;
"AGND"
$PN"2"21;
"VCC"
$PN"3"39;
"REFIN"
$PN"39"43;
"PWM"
$PN"34"40;
%"Q_RES"
"2","(-3475,2800)","0","pure_quanta","I41";
;
PART_NUMBER"CS00002JB13"
PACK_TYPE"0402LF"
VALUE"0"
TOLERANCE"5%"
MATERIAL"EMPTY"
WATTAGE"1/16W"
LOCATION"PR640"
CDS_LIB"pure_quanta"
$SEC"1"
CDS_SEC"1";
"A"
$PN"1"3;
"B"
$PN"2"38;
%"VCC15"
"1","(-3475,3025)","0","logical_power","I42";
;
HDL_POWER"P3V3"
CDS_LIB"logical_power";
"A"3;
%"UNIVERSAL_GND"
"1","(-1450,400)","0","logical_power","I43";
;
HDL_POWER"GND"
CDS_LIB"logical_power";
"A"21;
%"Q_CAP"
"1","(-1300,2025)","0","pure_quanta","I44";
;
PART_NUMBER"TMP_QCH2336K1B12"
PACK_TYPE"0402"
VOLTAGE"50V"
VALUE"3300PF"
TOLERANCE"10%"
MATERIAL"X7R"
LOCATION"PC561_P1_1"
CDS_LIB"pure_quanta"
LOCATION"PC561_P1_1"
$SEC"1"
CDS_SEC"1";
"B"
$PN"2"26;
"A"
$PN"1"7;
%"Q_RES"
"1","(-850,1575)","0","pure_quanta","I46";
;
PART_NUMBER"CS-3302FB01"
TOLERANCE"1%"
MATERIAL"CHIP"
WATTAGE"1/16W"
PACK_TYPE"0402LF"
VALUE"3.3"
LOCATION"PR1767"
CDS_LIB"pure_quanta"
$SEC"1"
CDS_SEC"1";
"B"
$PN"2"33;
"A"
$PN"1"36;
%"Q_CAP"
"1","(-900,2025)","0","pure_quanta","I47";
;
PART_NUMBER"CH5103KEB01"
PACK_TYPE"C0402"
VOLTAGE"16V"
VALUE"1UF"
MATERIAL"X6S"
TOLERANCE"10%"
LOCATION"PC563_P1_1"
CDS_LIB"pure_quanta"
LOCATION"PC563_P1_1"
$SEC"1"
CDS_SEC"1";
"B"
$PN"2"26;
"A"
$PN"1"7;
%"Q_CAP"
"1","(-500,2025)","0","pure_quanta","I48";
;
PART_NUMBER"CH6223MEA01"
TOLERANCE"20%"
PACK_TYPE"C0805"
VOLTAGE"16V"
VALUE"22UF"
MATERIAL"X6S"
LOCATION"PC567_P1_1"
CDS_LIB"pure_quanta"
LOCATION"PC567_P1_1"
$SEC"1"
CDS_SEC"1";
"B"
$PN"2"26;
"A"
$PN"1"7;
%"Q_CAP"
"1","(-125,1400)","2","pure_quanta","I49";
;
PART_NUMBER"CH4106K1B01"
PACK_TYPE"C0402"
VOLTAGE"50V"
VALUE"100NF"
TOLERANCE"10%"
MATERIAL"X7R"
LOCATION"PC565"
CDS_LIB"pure_quanta"
$SEC"1"
CDS_SEC"1";
"B"
$PN"2"35;
"A"
$PN"1"33;
%"Q_CAP"
"1","(-100,2025)","0","pure_quanta","I50";
;
PART_NUMBER"CH6223MEA01"
TOLERANCE"20%"
PACK_TYPE"C0805"
VOLTAGE"16V"
VALUE"22UF"
MATERIAL"X6S"
LOCATION"PC569_P1_1"
CDS_LIB"pure_quanta"
LOCATION"PC569_P1_1"
$SEC"1"
CDS_SEC"1";
"B"
$PN"2"26;
"A"
$PN"1"7;
%"Q_RES"
"1","(375,-2250)","0","pure_quanta","I51";
;
PART_NUMBER"CS00002JB13"
PACK_TYPE"0402LF"
VALUE"0"
TOLERANCE"5%"
MATERIAL"CHIP"
WATTAGE"1/16W"
LOCATION"PR329"
CDS_LIB"pure_quanta"
$SEC"1"
CDS_SEC"1";
"B"
$PN"2"5;
"A"
$PN"1"50;
%"Q_CAP"
"1","(250,-800)","0","pure_quanta","I53";
;
PART_NUMBER"CH6223MEA01"
TOLERANCE"20%"
PACK_TYPE"C0805"
VOLTAGE"16V"
VALUE"22UF"
MATERIAL"X6S"
LOCATION"PC570_P1_2"
CDS_LIB"pure_quanta"
LOCATION"PC570_P1_2"
$SEC"1"
CDS_SEC"1";
"B"
$PN"2"22;
"A"
$PN"1"4;
%"UNIVERSAL_GND"
"1","(475,-1225)","0","logical_power","I54";
;
HDL_POWER"GND"
CDS_LIB"logical_power";
"A"22;
%"VCC15"
"1","(475,-425)","0","logical_power","I55";
;
HDL_POWER"SW_P12V_PVCCIN_CPU1_FLT"
CDS_LIB"logical_power";
"A"4;
%"Q_CAPP"
"1","(2025,-50)","0","pure_quanta","I56";
;
PART_NUMBER"CC7560JMD16"
PACK_TYPE"THLF"
VALUE"560UF"
TOLERANCE"20%"
MATERIAL"OSCON"
VOLTAGE"2.5V"
LOCATION"PC83"
CDS_LIB"pure_quanta"
$SEC"1"
CDS_SEC"1";
"A"
$PN"1"9;
"B"
$PN"2"25;
%"Q_CAP"
"1","(2775,-1975)","0","pure_quanta","I57";
;
PART_NUMBER"CH622KMEA03"
TOLERANCE"20%"
VOLTAGE"4V"
VALUE"22UF"
MATERIAL"X6S"
PACK_TYPE"C0805"
LOCATION"PC575_P1_2"
CDS_LIB"pure_quanta"
LOCATION"PC575_P1_2"
$SEC"1"
CDS_SEC"1";
"B"
$PN"2"23;
"A"
$PN"1"5;
%"Q_CAP"
"1","(3200,-1975)","0","pure_quanta","I58";
;
PART_NUMBER"CH622KMEA03"
TOLERANCE"20%"
VALUE"22UF"
PACK_TYPE"C0805"
VOLTAGE"4V"
MATERIAL"X6S"
LOCATION"PC577_P1_2"
CDS_LIB"pure_quanta"
LOCATION"PC577_P1_2"
$SEC"1"
CDS_SEC"1";
"B"
$PN"2"23;
"A"
$PN"1"5;
%"Q_RES"
"2","(3700,-1975)","0","pure_quanta","I59";
;
PART_NUMBER"CS14992FB06"
PACK_TYPE"0402LF"
MATERIAL"CHIP"
WATTAGE"1/16W"
VALUE"499"
TOLERANCE"1%"
LOCATION"PR4240"
CDS_LIB"pure_quanta"
BOM_COST"VR_PCH"
$SEC"1"
CDS_SEC"1";
"A"
$PN"1"5;
"B"
$PN"2"23;
%"Q_CAP"
"2","(-3325,-1900)","0","pure_quanta","I6";
;
PART_NUMBER"CH4104K1B00"
TOLERANCE"10%"
MATERIAL"X7R"
VALUE"0.1UF"
VOLTAGE"25V"
PACK_TYPE"0402"
LOCATION"PC1338"
CDS_LIB"pure_quanta"
$SEC"1"
CDS_SEC"1";
"A"
$PN"1"12;
"B"
$PN"2"53;
%"UNIVERSAL_GND"
"1","(4075,-2375)","0","logical_power","I60";
;
HDL_POWER"GND"
CDS_LIB"logical_power";
"A"23;
%"Q_CAPP"
"1","(2600,-950)","0","pure_quanta","I61";
;
PART_NUMBER"CH733LY8802"
VALUE"330UF"
MATERIAL"EMPTY"
VOLTAGE"2.5V"
PACK_TYPE"SMLF"
TOLERANCE"+10/-35%"
LOCATION"PC1990"
CDS_LIB"pure_quanta"
$SEC"1"
CDS_SEC"1";
"A"
$PN"1"6;
"B"
$PN"2"24;
%"Q_CAPP"
"1","(3100,-925)","0","pure_quanta","I62";
;
PART_NUMBER"CH733LY8802"
MATERIAL"EMPTY"
VOLTAGE"2.5V"
TOLERANCE"+10/-35%"
VALUE"330UF"
PACK_TYPE"SMLF"
LOCATION"PC189"
CDS_LIB"pure_quanta"
$SEC"1"
CDS_SEC"1";
"A"
$PN"1"6;
"B"
$PN"2"24;
%"Q_CAPP"
"1","(2500,-75)","0","pure_quanta","I63";
;
PART_NUMBER"CC7560JMD16"
PACK_TYPE"THLF"
VALUE"560UF"
TOLERANCE"20%"
MATERIAL"OSCON"
VOLTAGE"2.5V"
LOCATION"PC580"
CDS_LIB"pure_quanta"
LOCATION"PC580"
$SEC"1"
CDS_SEC"1";
"A"
$PN"1"9;
"B"
$PN"2"25;
%"Q_CAPP"
"1","(3025,-75)","0","pure_quanta","I64";
;
PART_NUMBER"CC7560JMD16"
PACK_TYPE"THLF"
VALUE"560UF"
TOLERANCE"20%"
MATERIAL"OSCON"
VOLTAGE"2.5V"
LOCATION"PC583"
CDS_LIB"pure_quanta"
LOCATION"PC583"
$SEC"1"
CDS_SEC"1";
"A"
$PN"1"9;
"B"
$PN"2"25;
%"Q_CAPP"
"1","(3550,-950)","0","pure_quanta","I65";
;
PART_NUMBER"CH733LY8802"
VALUE"330UF"
TOLERANCE"+10/-35%"
VOLTAGE"2.5V"
PACK_TYPE"SMLF"
MATERIAL"EMPTY"
LOCATION"PC587"
CDS_LIB"pure_quanta"
LOCATION"PC587"
$SEC"1"
CDS_SEC"1";
"A"
$PN"1"6;
"B"
$PN"2"24;
%"VCC15"
"1","(4075,-1675)","0","logical_power","I66";
;
HDL_POWER"PVCCIN_CPU1"
CDS_LIB"logical_power";
"A"5;
%"UNIVERSAL_GND"
"1","(4050,-1275)","0","logical_power","I67";
;
HDL_POWER"GND"
CDS_LIB"logical_power";
"A"24;
%"Q_CAPP"
"1","(4050,-950)","0","pure_quanta","I68";
;
PART_NUMBER"CH733LY8802"
VOLTAGE"2.5V"
PACK_TYPE"SMLF"
MATERIAL"EMPTY"
VALUE"330UF"
TOLERANCE"+10/-35%"
LOCATION"PC590"
CDS_LIB"pure_quanta"
LOCATION"PC590"
$SEC"1"
CDS_SEC"1";
"A"
$PN"1"6;
"B"
$PN"2"24;
%"Q_CAPP"
"1","(3550,-75)","0","pure_quanta","I69";
;
PART_NUMBER"CC7560JMD16"
PACK_TYPE"THLF"
VALUE"560UF"
TOLERANCE"20%"
MATERIAL"OSCON"
VOLTAGE"2.5V"
LOCATION"PC586"
CDS_LIB"pure_quanta"
LOCATION"PC586"
$SEC"1"
CDS_SEC"1";
"A"
$PN"1"9;
"B"
$PN"2"25;
%"ISL99390FRZTR5935"
"1","(-2125,-1700)","0","pure_quanta","I7";
;
PART_NUMBER"AL099390004"
MATERIAL"IC"
PART_TYPE"SMLF"
VALUE"ISL99390FRZ-TR5935"
LOCATION"PU30_P1_2"
CDS_LIB"pure_quanta"
CDS_LMAN_SYM_OUTLINE"-300,700,250,-650"
NEEDS_NO_SIZE"TRUE"
$SEC"1"
CDS_SEC"1";
"PGND2"
$PN"7_9-20_24"16;
"GL2"
$PN"41"0;
"GL1"
$PN"6"0;
"DNC"
$PN"31"0;
"EN"
$PN"35"51;
"PGND3"
$PN"40"16;
"VOS"
$PN"1"50;
"VIN2"
$PN"30"4;
"PGND1"
$PN"5"16;
"SW"
$PN"10_19"46;
"LSET"
$PN"37"56;
"IOUT"
$PN"38"52;
"TOUT_FLT"
$PN"36"55;
"PVCC"
$PN"4"1;
"PHASE"
$PN"32"47;
"VIN1"
$PN"25_29"4;
"BOOT"
$PN"33"48;
"AGND"
$PN"2"16;
"VCC"
$PN"3"51;
"REFIN"
$PN"39"53;
"PWM"
$PN"34"54;
%"VCC15"
"1","(4050,-625)","0","logical_power","I70";
;
HDL_POWER"PVCCIN_CPU1"
CDS_LIB"logical_power";
"A"6;
%"UNIVERSAL_GND"
"1","(4050,-400)","0","logical_power","I71";
;
HDL_POWER"GND"
CDS_LIB"logical_power";
"A"25;
%"Q_CAPP"
"1","(4050,-75)","0","pure_quanta","I72";
;
PART_NUMBER"CC7560JMD16"
PACK_TYPE"THLF"
VALUE"560UF"
TOLERANCE"20%"
MATERIAL"OSCON"
VOLTAGE"2.5V"
LOCATION"PC589"
CDS_LIB"pure_quanta"
LOCATION"PC589"
$SEC"1"
CDS_SEC"1";
"A"
$PN"1"9;
"B"
$PN"2"25;
%"Q_RES"
"1","(175,600)","0","pure_quanta","I73";
;
PART_NUMBER"CS00002JB13"
MATERIAL"CHIP"
PACK_TYPE"0402LF"
TOLERANCE"5%"
VALUE"0"
WATTAGE"1/16W"
LOCATION"PR330"
CDS_LIB"pure_quanta"
$SEC"1"
CDS_SEC"1";
"B"
$PN"2"10;
"A"
$PN"1"34;
%"Q_INDUCTOR4P_14"
"1","(775,1025)","0","pure_quanta","I74";
;
PART_NUMBER"CV+15^0TZ04"
PART_TYPE"SMLF"
MATERIAL"IND"
VALUE"150NH"
LOCATION"PL31"
SEC_TYPE""
CDS_LIB"pure_quanta"
NEEDS_NO_SIZE"TRUE"
SEC"1";
"1"
$PN"1"37;
"4"
$PN"4"10;
"3"
$PN"3"30;
"2"
$PN"2"32;
%"UNIVERSAL_GND"
"1","(500,1600)","0","logical_power","I75";
;
HDL_POWER"GND"
CDS_LIB"logical_power";
"A"26;
%"Q_CAP"
"1","(275,2025)","0","pure_quanta","I76";
;
PART_NUMBER"CH6223MEA01"
TOLERANCE"20%"
MATERIAL"X6S"
PACK_TYPE"C0805"
VOLTAGE"16V"
VALUE"22UF"
LOCATION"PC571_P1_1"
CDS_LIB"pure_quanta"
LOCATION"PC571_P1_1"
$SEC"1"
CDS_SEC"1";
"B"
$PN"2"26;
"A"
$PN"1"7;
%"GND"
"1","(1400,2000)","0","logical_power","I78";
;
HDL_POWER"GND"
SIZE"1B"
CDS_LIB"logical_power";
"A<SIZE-1..0>\NAC"27;
%"Q_CAP"
"1","(1400,2250)","2","pure_quanta","I79";
;
PART_NUMBER"CH4106K1B01"
TOLERANCE"10%"
PACK_TYPE"C0402"
MATERIAL"X7R"
VOLTAGE"50V"
VALUE"100NF"
LOCATION"PC1656"
CDS_LIB"pure_quanta"
$SEC"1"
CDS_SEC"1";
"B"
$PN"2"27;
"A"
$PN"1"8;
%"VCC15"
"1","(500,2400)","0","logical_power","I80";
;
HDL_POWER"SW_P12V_PVCCIN_CPU1_FLT"
CDS_LIB"logical_power";
"A"7;
%"VCC15"
"1","(1400,2625)","0","logical_power","I81";
;
HDL_POWER"P12V_AUX"
CDS_LIB"logical_power";
"A"8;
%"Q_RES"
"1","(1925,2325)","0","pure_quanta","I82";
;
PART_NUMBER"TMP_QCS+0308BR00"
PACK_TYPE"2512LF"
MATERIAL"EMPTY"
WATTAGE"1W"
VALUE"0.03"
TOLERANCE"0.1%"
LOCATION"PR2556"
CDS_LIB"pure_quanta"
$SEC"1"
CDS_SEC"1";
"B"
$PN"2"11;
"A"
$PN"1"8;
%"Q_INDUCTOR"
"1","(1925,2475)","0","pure_quanta","I83";
;
PART_NUMBER"CVA50^0EZ01"
PACK_TYPE"SMLF"
VALUE"50NH/148A"
MATERIAL"IND"
LOCATION"PL32"
NEEDS_NO_SIZE"TRUE"
CDS_LIB"pure_quanta"
$SEC"1"
CDS_SEC"1";
"1"
$PN"1"8;
"2"
$PN"2"11;
%"Q_CAP"
"1","(2550,950)","0","pure_quanta","I84";
;
PART_NUMBER"CH4106K1B01"
VOLTAGE"50V"
VALUE"100NF"
TOLERANCE"10%"
MATERIAL"X7R"
PACK_TYPE"C0402"
LOCATION"PC572_P1_1"
CDS_LIB"pure_quanta"
LOCATION"PC572_P1_1"
$SEC"1"
CDS_SEC"1";
"B"
$PN"2"28;
"A"
$PN"1"10;
%"Q_CAP"
"1","(2950,950)","0","pure_quanta","I85";
;
PART_NUMBER"CH5103KEB01"
TOLERANCE"10%"
VALUE"1UF"
VOLTAGE"16V"
PACK_TYPE"C0402"
MATERIAL"X6S"
LOCATION"PC574_P1_1"
CDS_LIB"pure_quanta"
LOCATION"PC574_P1_1"
$SEC"1"
CDS_SEC"1";
"B"
$PN"2"28;
"A"
$PN"1"10;
%"Q_CAPP"
"1","(2500,2250)","0","pure_quanta","I86";
;
PART_NUMBER"CC72703MD38"
VALUE"270UF"
TOLERANCE"20%"
VOLTAGE"16V"
MATERIAL"OSCON"
PACK_TYPE"THLF"
LOCATION"PC579"
CDS_LIB"pure_quanta"
LOCATION"PC579"
$SEC"1"
CDS_SEC"1";
"A"
$PN"1"11;
"B"
$PN"2"29;
%"Q_CAPP"
"1","(2900,2250)","0","pure_quanta","I87";
;
PART_NUMBER"CC72703MD38"
VOLTAGE"16V"
TOLERANCE"20%"
MATERIAL"OSCON"
PACK_TYPE"THLF"
VALUE"270UF"
LOCATION"PC582"
CDS_LIB"pure_quanta"
LOCATION"PC582"
$SEC"1"
CDS_SEC"1";
"A"
$PN"1"11;
"B"
$PN"2"29;
%"Q_CAP"
"1","(3375,950)","0","pure_quanta","I88";
;
PART_NUMBER"CH622KMEA03"
VOLTAGE"4V"
TOLERANCE"20%"
VALUE"22UF"
MATERIAL"X6S"
PACK_TYPE"C0805"
LOCATION"PC576_P1_1"
CDS_LIB"pure_quanta"
LOCATION"PC576_P1_1"
$SEC"1"
CDS_SEC"1";
"B"
$PN"2"28;
"A"
$PN"1"10;
%"VCC15"
"1","(4050,250)","0","logical_power","I89";
;
HDL_POWER"PVCCIN_CPU1"
CDS_LIB"logical_power";
"A"9;
%"UNIVERSAL_GND"
"1","(4100,575)","0","logical_power","I90";
;
HDL_POWER"GND"
CDS_LIB"logical_power";
"A"28;
%"Q_CAP"
"1","(3800,950)","0","pure_quanta","I91";
;
PART_NUMBER"CH622KMEA03"
TOLERANCE"20%"
MATERIAL"X6S"
VALUE"22UF"
VOLTAGE"4V"
PACK_TYPE"C0805"
LOCATION"PC578_P1_1"
CDS_LIB"pure_quanta"
LOCATION"PC578_P1_1"
$SEC"1"
CDS_SEC"1";
"B"
$PN"2"28;
"A"
$PN"1"10;
%"Q_CAPP"
"1","(3300,2250)","0","pure_quanta","I92";
;
PART_NUMBER"CC72703MD38"
VOLTAGE"16V"
TOLERANCE"20%"
PACK_TYPE"THLF"
MATERIAL"OSCON"
VALUE"270UF"
LOCATION"PC585"
CDS_LIB"pure_quanta"
LOCATION"PC585"
$SEC"1"
CDS_SEC"1";
"A"
$PN"1"11;
"B"
$PN"2"29;
%"VCC15"
"1","(4100,1350)","0","logical_power","I93";
;
HDL_POWER"PVCCIN_CPU1"
CDS_LIB"logical_power";
"A"10;
%"Q_CAPP"
"1","(3700,2250)","0","pure_quanta","I94";
;
PART_NUMBER"CC72703MD38"
MATERIAL"OSCON"
VOLTAGE"16V"
VALUE"270UF"
TOLERANCE"20%"
PACK_TYPE"THLF"
LOCATION"PC588"
CDS_LIB"pure_quanta"
LOCATION"PC588"
$SEC"1"
CDS_SEC"1";
"A"
$PN"1"11;
"B"
$PN"2"29;
%"UNIVERSAL_GND"
"1","(4100,1925)","0","logical_power","I95";
;
HDL_POWER"GND"
CDS_LIB"logical_power";
"A"29;
%"Q_CAPP"
"1","(4100,2250)","0","pure_quanta","I96";
;
PART_NUMBER"CC72703MD38"
VALUE"270UF"
TOLERANCE"20%"
VOLTAGE"16V"
MATERIAL"OSCON"
PACK_TYPE"THLF"
LOCATION"PC2346"
CDS_LIB"pure_quanta"
$SEC"1"
CDS_SEC"1";
"A"
$PN"1"11;
"B"
$PN"2"29;
%"VCC15"
"1","(4100,2575)","0","logical_power","I97";
;
HDL_POWER"SW_P12V_PVCCIN_CPU1_FLT"
CDS_LIB"logical_power";
"A"11;
END.
